FILE_TYPE = CONNECTIVITY;
{Allegro Design Entry HDL 17.2-2016 S081 (4005846) 1/11/2022}
"PAGE_NUMBER" = 193;
0"NC";
1"FM_ADR_TRIGGER_R_N"CDS_PHYS_NET_NAME"FM_ADR_TRIGGER_R_N";
2"FM_CPU_RMCA_CATERR_DLY_N";
3"FM_ADR_TRIGGER_N"CDS_PHYS_NET_NAME"FM_ADR_TRIGGER_N";
4"FM_ADR_MODE0_R";
5"FM_ADR_MODE0";
6"FM_CPU_RMCA_CATERR_DLY_LVT3_R_N";
7"FM_BIOS_POST_CMPLT_HDR_N";
8"FM_BIOS_POST_CMPLT_BMC_N";
9"FM_PCH_PLD_GLB_RST_WARN_N";
10"IRQ_PCH_CPU_NMI_EVENT_N";
11"FM_BIOS_POST_CMPLT_N";
12"FM_PCH_GLB_RST_WARN_N";
13"IRQ_PCH_CPU_NMI_EVENT_R_N";
14"FM_PS_PWROK_DLY_R_SEL";
15"FM_PS_PWROK_DLY_SEL";
16"IRQ_SMI_ACTIVE_N";
17"IRQ_SMI_ACTIVE_BMC_N";
18"FM_THROTTLE_N";
19"FM_THROTTLE_R_N";
%"Q_RES"
"1","(-5700,75)","0","pure_quanta","I10";
;
PART_NUMBER"CS03322FB03"
MATERIAL"CHIP"
WATTAGE"1/16W"
PACK_TYPE"0402LF"
TOLERANCE"1%"
VALUE"33.2"
$LOCATION"R1309"
CDS_LIB"pure_quanta"
$LOCATION"R1309"
CDS_LOCATION"R1309"
$SEC"1"
CDS_SEC"1";
"B"
$PN"2"17;
"A"
$PN"1"16;
%"Q_RES"
"1","(-5700,625)","0","pure_quanta","I13";
;
PART_NUMBER"CS03322FB03"
VALUE"33.2"
MATERIAL"CHIP"
WATTAGE"1/16W"
PACK_TYPE"0402LF"
TOLERANCE"1%"
$LOCATION"R1306"
CDS_LIB"pure_quanta"
$LOCATION"R1306"
CDS_LOCATION"R1306"
$SEC"1"
CDS_SEC"1";
"B"
$PN"2"15;
"A"
$PN"1"14;
%"Q_RES"
"1","(-5700,-225)","0","pure_quanta","I20";
;
PART_NUMBER"CS03322FB03"
WATTAGE"1/16W"
PACK_TYPE"0402LF"
TOLERANCE"1%"
VALUE"33.2"
MATERIAL"CHIP"
$LOCATION"R1310"
CDS_LIB"pure_quanta"
$LOCATION"R1310"
CDS_LOCATION"R1310"
$SEC"1"
CDS_SEC"1";
"B"
$PN"2"10;
"A"
$PN"1"13;
%"Q_RES"
"1","(-5700,-525)","0","pure_quanta","I21";
;
PART_NUMBER"CS03322FB03"
MATERIAL"CHIP"
TOLERANCE"1%"
VALUE"33.2"
PACK_TYPE"0402LF"
WATTAGE"1/16W"
$LOCATION"R1313"
CDS_LIB"pure_quanta"
$LOCATION"R1313"
CDS_LOCATION"R1313"
$SEC"1"
CDS_SEC"1";
"B"
$PN"2"9;
"A"
$PN"1"12;
%"Q_RES"
"1","(-5725,-1575)","0","pure_quanta","I27";
;
PART_NUMBER"CS04992FB07"
PACK_TYPE"0402LF"
WATTAGE"1/16W"
TOLERANCE"1%"
MATERIAL"CHIP"
VALUE"49.9"
$LOCATION"R1455"
CDS_LIB"pure_quanta"
CDS_LOCATION"R1455"
$SEC"1"
CDS_SEC"1";
"B"
$PN"2"5;
"A"
$PN"1"4;
%"Q_RES"
"1","(-5725,-1800)","0","pure_quanta","I28";
;
PART_NUMBER"CS04992FB07"
PACK_TYPE"0402LF"
WATTAGE"1/16W"
TOLERANCE"1%"
MATERIAL"CHIP"
VALUE"49.9"
$LOCATION"R1456"
CDS_LIB"pure_quanta"
CDS_LOCATION"R1456"
$SEC"1"
CDS_SEC"1";
"B"
$PN"2"2;
"A"
$PN"1"6;
%"Q_RES"
"1","(-5700,350)","0","pure_quanta","I3";
;
PART_NUMBER"CS03322FB03"
VALUE"33.2"
MATERIAL"CHIP"
TOLERANCE"1%"
WATTAGE"1/16W"
PACK_TYPE"0402LF"
$LOCATION"R1307"
CDS_LIB"pure_quanta"
$LOCATION"R1307"
CDS_LOCATION"R1307"
$SEC"1"
CDS_SEC"1";
"B"
$PN"2"19;
"A"
$PN"1"18;
%"Q_RES"
"1","(-5725,-2275)","0","pure_quanta","I32";
;
PART_NUMBER"CS04992FB07"
TOLERANCE"1%"
VALUE"49.9"
PACK_TYPE"0402LF"
WATTAGE"1/16W"
MATERIAL"CHIP"
$LOCATION"R698"
CDS_LIB"pure_quanta"
CDS_LOCATION"R698"
$SEC"1"
CDS_SEC"1";
"B"
$PN"2"3;
"A"
$PN"1"1;
%"Q_RES"
"1","(-5750,-1025)","0","pure_quanta","I40";
;
PART_NUMBER"CS03322FB03"
VALUE"33.2"
PACK_TYPE"0402LF"
WATTAGE"1/16W"
TOLERANCE"1%"
MATERIAL"CHIP"
$LOCATION"R3065"
CDS_LIB"pure_quanta"
CDS_LOCATION"R3065"
$SEC"1"
CDS_SEC"1";
"B"
$PN"2"7;
"A"
$PN"1"11;
%"Q_RES"
"1","(-5725,-825)","0","pure_quanta","I5";
;
PART_NUMBER"CS03322FB03"
MATERIAL"CHIP"
TOLERANCE"1%"
WATTAGE"1/16W"
PACK_TYPE"0402LF"
VALUE"33.2"
$LOCATION"R1300"
CDS_LIB"pure_quanta"
$LOCATION"R1300"
CDS_LOCATION"R1300"
$SEC"1"
CDS_SEC"1";
"B"
$PN"2"8;
"A"
$PN"1"11;
END.
